G04*
G04 #@! TF.GenerationSoftware,Altium Limited,Altium Designer,23.0.1 (38)*
G04*
G04 Layer_Color=0*
%FSLAX44Y44*%
%MOMM*%
G71*
G04*
G04 #@! TF.SameCoordinates,9A23C038-B079-480F-8166-AFFB5740F5AE*
G04*
G04*
G04 #@! TF.FilePolarity,Positive*
G04*
G01*
G75*
%ADD51C,0.0254*%
G36*
X618010Y28960D02*
Y27433D01*
X618606Y24439D01*
X619774Y21618D01*
X621470Y19079D01*
X623629Y16920D01*
X626168Y15224D01*
X628989Y14056D01*
X631983Y13460D01*
X633510D01*
X635037D01*
X638031Y14056D01*
X640852Y15224D01*
X643391Y16920D01*
X645550Y19079D01*
X647246Y21618D01*
X648414Y24439D01*
X649010Y27433D01*
Y28960D01*
Y30487D01*
X648414Y33481D01*
X647246Y36302D01*
X645550Y38841D01*
X643391Y41000D01*
X640852Y42696D01*
X638031Y43864D01*
X635037Y44460D01*
X633510D01*
X631983D01*
X628989Y43864D01*
X626168Y42696D01*
X623629Y41000D01*
X621470Y38841D01*
X619774Y36302D01*
X618606Y33481D01*
X618010Y30487D01*
Y28960D01*
D01*
D02*
G37*
G36*
X13010D02*
Y30487D01*
X13606Y33481D01*
X14774Y36302D01*
X16470Y38841D01*
X18629Y41000D01*
X21168Y42696D01*
X23989Y43864D01*
X26983Y44460D01*
X28510D01*
X30037D01*
X33031Y43864D01*
X35852Y42696D01*
X38391Y41000D01*
X40550Y38841D01*
X42246Y36302D01*
X43414Y33481D01*
X44010Y30487D01*
Y28960D01*
Y27433D01*
X43414Y24439D01*
X42246Y21618D01*
X40550Y19079D01*
X38391Y16920D01*
X35852Y15224D01*
X33031Y14056D01*
X30037Y13460D01*
X28510D01*
X26983D01*
X23989Y14056D01*
X21168Y15224D01*
X18629Y16920D01*
X16470Y19079D01*
X14774Y21618D01*
X13606Y24439D01*
X13010Y27433D01*
Y28960D01*
D01*
D02*
G37*
G36*
X618010Y288960D02*
Y287433D01*
X618606Y284439D01*
X619774Y281618D01*
X621470Y279079D01*
X623629Y276920D01*
X626168Y275224D01*
X628989Y274056D01*
X631983Y273460D01*
X633510D01*
X635037D01*
X638031Y274056D01*
X640852Y275224D01*
X643391Y276920D01*
X645550Y279079D01*
X647246Y281618D01*
X648414Y284439D01*
X649010Y287433D01*
Y288960D01*
Y290487D01*
X648414Y293481D01*
X647246Y296302D01*
X645550Y298841D01*
X643391Y301000D01*
X640852Y302696D01*
X638031Y303864D01*
X635037Y304460D01*
X633510D01*
X631983D01*
X628989Y303864D01*
X626168Y302696D01*
X623629Y301000D01*
X621470Y298841D01*
X619774Y296302D01*
X618606Y293481D01*
X618010Y290487D01*
Y288960D01*
D01*
D02*
G37*
G36*
X28510Y273460D02*
X26983D01*
X23989Y274056D01*
X21168Y275224D01*
X18629Y276920D01*
X16470Y279079D01*
X14774Y281618D01*
X13606Y284439D01*
X13010Y287433D01*
Y288960D01*
Y290487D01*
X13606Y293481D01*
X14774Y296302D01*
X16470Y298841D01*
X18629Y301000D01*
X21168Y302696D01*
X23989Y303864D01*
X26983Y304460D01*
X28510D01*
X30037D01*
X33031Y303864D01*
X35852Y302696D01*
X38391Y301000D01*
X40550Y298841D01*
X42246Y296302D01*
X43414Y293481D01*
X44010Y290487D01*
Y288960D01*
Y287433D01*
X43414Y284439D01*
X42246Y281618D01*
X40550Y279079D01*
X38391Y276920D01*
X35852Y275224D01*
X33031Y274056D01*
X30037Y273460D01*
X28510D01*
D01*
D02*
G37*
D51*
X10450Y0D02*
G02*
X0Y10450I0J10450D01*
G01*
X-20Y306760D01*
D02*
G02*
X10680Y317470I10710J0D01*
G01*
X660940Y317490D01*
D02*
G02*
X671740Y306700I0J-10800D01*
G01*
X671710Y10150D01*
D02*
G02*
X661530Y-40I-10190J-0D01*
G01*
X10450Y0D01*
M02*
